FILE_TYPE = MULTI_PHYS_TABLE;
PART 'FERRITE'
{===============================================================================================================================================================================================================================================================}
:VALUE | PACK_TYPE | MATERIAL | PART_NUMBER    = EnvComp                   | PART_NUMBER  | JEDEC_TYPE | ALT_SYMBOLS          | VALUE   | CLASS      | DESCRIPTION                               | COMPONENT_TYPE | HEIGHT     | LEAD_LENGTH | LPID   | SPEED_URL                                                                                                                        | Status |RPL| AML | Bus_Unit | Days ;
{===============================================================================================================================================================================================================================================================}
'600'  | 'SMLF'    | 'FB'     | '656554-043'(!) = 'YES;YES;YES;UNK;ok;VLD' | '656554-043' | 'SFB0805A' | '(SMX0805)'          | '600'   | 'DISCRETE' | 'FERRITE 600OHM'                          | 'CHIP'         | '0.040 IN' | ''          | ''     | 'http://speed.intel.com:8081/speed/module/pdm/item/pdm_item_detail_direct.asp?item_cde=656554-043&item_rev=01&url_param=unused' | 'Conditional' | 'YES' | '3' | 'SMO_BOARDS' | '56' 
'600'  | 'SMLF'    | 'EMPTY'  | '656554-043'(!) = 'YES;YES;YES;UNK;ok;VLD' | '656554-043' | 'SFB0805A' | '(SMX0805)'          | 'NA'    | 'DISCRETE' | 'FERRITE 600OHM'                          | 'CHIP'         | '0.040 IN' | ''          | ''     | 'http://speed.intel.com:8081/speed/module/pdm/item/pdm_item_detail_direct.asp?item_cde=656554-043&item_rev=01&url_param=unused' | 'Conditional' | 'YES' | '3' | 'SMO_BOARDS' | '56' 
'60'   | 'SMLF'    | 'FB'     | '693286-001'(!) = 'YES;YES;YES;UNK;ok;VLD' | '693286-001' | 'SFB0603A' | '(SMX0603)'          | '60'    | 'DISCRETE' | 'FERRITE 60OHM'                           | 'CHIP'         | '0.038 IN' | ''          | ''     | 'http://speed.intel.com:8081/speed/module/pdm/item/pdm_item_detail_direct.asp?item_cde=693286-001&item_rev=01&url_param=unused' | 'Approved' | 'YES' | '9' | 'SMO_BOARDS' | '56' 
'60'   | 'SM'      | 'FB'     | '693286-001'(!) = 'YES;YES;YES;UNK;ok;VLD' | '693286-001' | 'SFB0603A' | '(SMX0603)'          | '60'    | 'DISCRETE' | 'FERRITE 60OHM'                           | 'CHIP'         | '0.038 IN' | ''          | ''     | 'http://speed.intel.com:8081/speed/module/pdm/item/pdm_item_detail_direct.asp?item_cde=693286-001&item_rev=01&url_param=unused' | 'Approved' | 'YES' | '9' | 'SMO_BOARDS' | '56' 
'60'   | 'SMLF'    | 'EMPTY'  | '693286-001'(!) = 'YES;YES;YES;UNK;ok;VLD' | '693286-001' | 'SFB0603A' | '(SMX0603)'          | 'NA'    | 'DISCRETE' | 'FERRITE 60OHM'                           | 'CHIP'         | '0.038 IN' | ''          | ''     | 'http://speed.intel.com:8081/speed/module/pdm/item/pdm_item_detail_direct.asp?item_cde=693286-001&item_rev=01&url_param=unused' | 'Approved' | 'YES' | '9' | 'SMO_BOARDS' | '56' 
'60'   | 'SM'      | 'EMPTY'  | '693286-001'(!) = 'YES;YES;YES;UNK;ok;VLD' | '693286-001' | 'SFB0603A' | '(SMX0603)'          | 'NA'    | 'DISCRETE' | 'FERRITE 60OHM'                           | 'CHIP'         | '0.038 IN' | ''          | ''     | 'http://speed.intel.com:8081/speed/module/pdm/item/pdm_item_detail_direct.asp?item_cde=693286-001&item_rev=01&url_param=unused' | 'Approved' | 'YES' | '9' | 'SMO_BOARDS' | '56' 
'30'   | 'SMLF'    | 'FB'     | '693286-021'(!) = 'YES;YES;YES;UNK;ok;VLD' | '693286-021' | 'SFB0603A' | '(SMX0603)'          | '30'    | 'DISCRETE' | 'FERRITE 30OHM 1A'                        | 'CHIP'         | '0.037 IN' | ''          | ''     | 'http://speed.intel.com:8081/speed/module/pdm/item/pdm_item_detail_direct.asp?item_cde=693286-021&item_rev=01&url_param=unused' | 'Approved' | 'YES' | '6' | 'SMO_BOARDS' | '56' 
'30'   | 'SMLF'    | 'EMPTY'  | '693286-021'(!) = 'YES;YES;YES;UNK;ok;VLD' | '693286-021' | 'SFB0603A' | '(SMX0603)'          | 'NA'    | 'DISCRETE' | 'FERRITE 30OHM 1A'                        | 'CHIP'         | '0.037 IN' | ''          | ''     | 'http://speed.intel.com:8081/speed/module/pdm/item/pdm_item_detail_direct.asp?item_cde=693286-021&item_rev=01&url_param=unused' | 'Approved' | 'YES' | '6' | 'SMO_BOARDS' | '56' 
'300'  | 'SMLF'    | 'FB'     | '693286-046'(!) = 'YES;YES;UNK;UNK;ok;VLD' | '693286-046' | 'SFB0603A' | '(SMX0603)'          | '300'   | 'DISCRETE' | 'FERRITE 300OHM 500MA'                    | 'CHIP'         | '0.032 IN' | ''          | ''     | 'http://speed.intel.com:8081/speed/module/pdm/item/pdm_item_detail_direct.asp?item_cde=693286-046&item_rev=01&url_param=unused' | 'Conditional' | 'YES' | '1' | 'SMO_BOARDS' | '???' 
'300'  | 'SMLF'    | 'EMPTY'  | '693286-046'(!) = 'YES;YES;UNK;UNK;ok;VLD' | '693286-046' | 'SFB0603A' | '(SMX0603)'          | 'NA'    | 'DISCRETE' | 'FERRITE 300OHM 500MA'                    | 'CHIP'         | '0.032 IN' | ''          | ''     | 'http://speed.intel.com:8081/speed/module/pdm/item/pdm_item_detail_direct.asp?item_cde=693286-046&item_rev=01&url_param=unused' | 'Conditional' | 'YES' | '1' | 'SMO_BOARDS' | '???' 
'22'   | 'SM'      | 'FB'     | '656554-051'(!) = 'YES;YES;YES;UNK;ok;VLD' | '656554-051' | 'SFB0805A' | '(SMX0805)'          | '22'    | 'DISCRETE' | 'FER-BEAD,0805,22.0OHM,6.0A,+/-25%'       | 'CHIP0805'     | '0.041 IN' | ''          | '458'  | 'http://speed.intel.com:8081/speed/module/pdm/item/pdm_item_detail_direct.asp?item_cde=656554-051&item_rev=01&url_param=unused' | 'Design' | 'YES' | '1' | 'SMO_BOARDS' | '???' 
'22'   | 'SM'      | 'EMPTY'  | '656554-051'(!) = 'YES;YES;YES;UNK;ok;VLD' | '656554-051' | 'SFB0805A' | '(SMX0805)'          | 'NA'    | 'DISCRETE' | 'FER-BEAD,0805,22.0OHM,6.0A,+/-25%'       | 'CHIP0805'     | '0.041 IN' | ''          | '458'  | 'http://speed.intel.com:8081/speed/module/pdm/item/pdm_item_detail_direct.asp?item_cde=656554-051&item_rev=01&url_param=unused' | 'Design' | 'YES' | '1' | 'SMO_BOARDS' | '???' 
'120'  | 'SM'      | 'FB'     | '693286-027'(!) = 'YES;YES;YES;UNK;ok;VLD' | '693286-027' | 'SFB0603B' | '(SMX0603)'          | '120'   | 'DISCRETE' | 'FER-BEAD,0603,120.0 OHM,2.0 A,+/- 25%'   | 'CHIP0603'     | '0.037 IN' | ''          | '2418' | 'http://speed.intel.com:8081/speed/module/pdm/item/pdm_item_detail_direct.asp?item_cde=693286-027&item_rev=01&url_param=unused' | 'Conditional' | 'YES' | '4' | 'SMO_BOARDS' | '56' 
'120'  | 'SM'      | 'EMPTY'  | '693286-027'(!) = 'YES;YES;YES;UNK;ok;VLD' | '693286-027' | 'SFB0603B' | '(SMX0603)'          | 'NA'    | 'DISCRETE' | 'FER-BEAD,0603,120.0 OHM,2.0 A,+/- 25%'   | 'CHIP0603'     | '0.037 IN' | ''          | '2418' | 'http://speed.intel.com:8081/speed/module/pdm/item/pdm_item_detail_direct.asp?item_cde=693286-027&item_rev=01&url_param=unused' | 'Conditional' | 'YES' | '4' | 'SMO_BOARDS' | '56' 
END_PART
END.
